(kicad_pcb
	(version 20221018)
	(generator pcbnew)
	(general
    (thickness 1.586)
  )
	(paper "A4")
	(title_block
    (date "2024-03-26")
    (rev "1.1.3")
		(comment 9 "footprints 119-121 of 146")
	)
	(layers
    (0 "F.Cu" signal)
    (1 "In1.Cu" power)
    (2 "In2.Cu" power)
    (31 "B.Cu" signal)
    (32 "B.Adhes" user "B.Adhesive")
    (33 "F.Adhes" user "F.Adhesive")
    (34 "B.Paste" user)
    (35 "F.Paste" user)
    (36 "B.SilkS" user "B.Silkscreen")
    (37 "F.SilkS" user "F.Silkscreen")
    (38 "B.Mask" user)
    (39 "F.Mask" user)
    (40 "Dwgs.User" user "User.Drawings")
    (41 "Cmts.User" user "User.Comments")
    (42 "Eco1.User" user "User.Eco1")
    (43 "Eco2.User" user "User.Eco2")
    (44 "Edge.Cuts" user)
    (45 "Margin" user)
    (46 "B.CrtYd" user "B.Courtyard")
    (47 "F.CrtYd" user "F.Courtyard")
    (48 "B.Fab" user)
    (49 "F.Fab" user)
  )
	(footprint "scalenode-cm4-baseboard-footprints:Bus_M.2_Socket_Key_M_Amphenol_MDT580M01001" locked (layer "B.Cu")
    (at 183.464 76.877 90)
    (property "Author" "Antmicro")
    (property "License" "Apache-2.0")
    (property "MPN" "MDT580M01001")
    (property "Manufacturer" "Amphenol")
    (property "Sheetfile" "nvme-ssd.kicad_sch")
    (property "Sheetname" "NVMe SSD")
    (property "ki_description" "PCI Express / PCI Connectors M.2 RA M Key 5.80H")
    (attr smd)
    (fp_text reference "J3" (at -10.013 5.926 90) (layer "B.SilkS")
        (effects (font (size 0.7 0.7) (thickness 0.15)) (justify right bottom mirror))
    )
    (fp_text value "Bus_M.2_MDT580M01001" (at 0 -5.9 90) (layer "B.Fab")
        (effects (font (size 0.7 0.7) (thickness 0.15)) (justify right bottom mirror))
    )
    (fp_text user "License: Apache-2.0" (at -13 -10.899 90) (layer "B.Fab") hide
        (effects (font (size 0.7 0.7) (thickness 0.15)) (justify right bottom mirror))
    )
    (fp_text user "Author: Antmicro" (at -13 -8.499 90) (layer "B.Fab") hide
        (effects (font (size 0.7 0.7) (thickness 0.15)) (justify right bottom mirror))
    )
    (fp_text user "${REFERENCE}" (at -13 -9.698 90) (layer "B.Fab") hide
        (effects (font (size 0.7 0.7) (thickness 0.15)) (justify right bottom mirror))
    )
    (fp_line (start -10.071 -4.626) (end -11.151 -4.626)
      (stroke (width 0.15) (type solid)) (layer "B.SilkS"))
    (fp_line (start -10.071 -4.626) (end -10.071 -2.205)
      (stroke (width 0.15) (type solid)) (layer "B.SilkS"))
    (fp_line (start -10.071 -0.624) (end 9.499 -0.624)
      (stroke (width 0.15) (type solid)) (layer "B.SilkS"))
    (fp_line (start 9.768 -4.626) (end 9.768 -2.346)
      (stroke (width 0.15) (type solid)) (layer "B.SilkS"))
    (fp_line (start 10.848 -4.626) (end 9.768 -4.626)
      (stroke (width 0.15) (type solid)) (layer "B.SilkS"))
    (fp_circle (center -9.7 4.7) (end -9.65 4.7)
      (stroke (width 0.15) (type solid)) (fill solid) (layer "B.SilkS"))
    (fp_rect (start -11.5 5) (end 11.5 -4.9)
      (stroke (width 0.05) (type solid)) (fill none) (layer "B.CrtYd"))
    (fp_line (start -10.985 4.13) (end -10.859 4.255)
      (stroke (width 0.15) (type solid)) (layer "B.Fab"))
    (fp_rect (start -11 -4.275) (end 10.999 4.276)
      (stroke (width 0.15) (type solid)) (fill none) (layer "B.Fab"))
    (pad "" np_thru_hole circle locked (at -10 -1.425 90) (size 1.1 1.1) (drill 1.1) (layers "F&B.Cu" "*.Mask"))
    (pad "" np_thru_hole circle locked (at 9.999 -1.425 90) (size 1.6 1.6) (drill 1.6) (layers "F&B.Cu" "*.Mask"))
    (pad "1" smd rect locked (at -9.25 3.848 90) (size 0.3 1.55) (layers "B.Cu" "B.Paste" "B.Mask")
      (net 11 "GND") (pinfunction "GND") (pintype "passive"))
    (pad "2" smd rect locked (at -9 -3.7 90) (size 0.3 1.55) (layers "B.Cu" "B.Paste" "B.Mask")
      (net 170 "3V3_SSD") (pinfunction "3V3") (pintype "passive"))
    (pad "3" smd rect locked (at -8.75 3.848 90) (size 0.3 1.55) (layers "B.Cu" "B.Paste" "B.Mask")
      (net 11 "GND") (pinfunction "GND") (pintype "passive"))
    (pad "4" smd rect locked (at -8.5 -3.7 90) (size 0.3 1.55) (layers "B.Cu" "B.Paste" "B.Mask")
      (net 170 "3V3_SSD") (pinfunction "3V3") (pintype "passive"))
    (pad "5" smd rect locked (at -8.25 3.848 90) (size 0.3 1.55) (layers "B.Cu" "B.Paste" "B.Mask")
      (net 163 "unconnected-(J3-PER3_N-Pad5)") (pinfunction "PER3_N") (pintype "passive+no_connect"))
    (pad "6" smd rect locked (at -8 -3.7 90) (size 0.3 1.55) (layers "B.Cu" "B.Paste" "B.Mask")
      (net 164 "unconnected-(J3-NC-Pad6)") (pinfunction "NC") (pintype "no_connect"))
    (pad "7" smd rect locked (at -7.75 3.848 90) (size 0.3 1.55) (layers "B.Cu" "B.Paste" "B.Mask")
      (net 165 "unconnected-(J3-PER3_P-Pad7)") (pinfunction "PER3_P") (pintype "passive+no_connect"))
    (pad "8" smd rect locked (at -7.5 -3.7 90) (size 0.3 1.55) (layers "B.Cu" "B.Paste" "B.Mask")
      (net 166 "unconnected-(J3-NC-Pad8)") (pinfunction "NC") (pintype "no_connect"))
    (pad "9" smd rect locked (at -7.25 3.848 90) (size 0.3 1.55) (layers "B.Cu" "B.Paste" "B.Mask")
      (net 11 "GND") (pinfunction "GND") (pintype "passive"))
    (pad "10" smd rect locked (at -7 -3.7 90) (size 0.3 1.55) (layers "B.Cu" "B.Paste" "B.Mask")
      (net 26 "Net-(J3-LED)") (pinfunction "LED") (pintype "passive"))
    (pad "11" smd rect locked (at -6.75 3.848 90) (size 0.3 1.55) (layers "B.Cu" "B.Paste" "B.Mask")
      (net 167 "unconnected-(J3-PET3_N-Pad11)") (pinfunction "PET3_N") (pintype "passive+no_connect"))
    (pad "12" smd rect locked (at -6.5 -3.7 90) (size 0.3 1.55) (layers "B.Cu" "B.Paste" "B.Mask")
      (net 170 "3V3_SSD") (pinfunction "3V3") (pintype "passive"))
    (pad "13" smd rect locked (at -6.25 3.848 90) (size 0.3 1.55) (layers "B.Cu" "B.Paste" "B.Mask")
      (net 168 "unconnected-(J3-PET3_P-Pad13)") (pinfunction "PET3_P") (pintype "passive+no_connect"))
    (pad "14" smd rect locked (at -6 -3.7 90) (size 0.3 1.55) (layers "B.Cu" "B.Paste" "B.Mask")
      (net 170 "3V3_SSD") (pinfunction "3V3") (pintype "passive"))
    (pad "15" smd rect locked (at -5.75 3.848 90) (size 0.3 1.55) (layers "B.Cu" "B.Paste" "B.Mask")
      (net 11 "GND") (pinfunction "GND") (pintype "passive"))
    (pad "16" smd rect locked (at -5.5 -3.7 90) (size 0.3 1.55) (layers "B.Cu" "B.Paste" "B.Mask")
      (net 170 "3V3_SSD") (pinfunction "3V3") (pintype "passive"))
    (pad "17" smd rect locked (at -5.25 3.848 90) (size 0.3 1.55) (layers "B.Cu" "B.Paste" "B.Mask")
      (net 169 "unconnected-(J3-PER2_N-Pad17)") (pinfunction "PER2_N") (pintype "passive+no_connect"))
    (pad "18" smd rect locked (at -5 -3.7 90) (size 0.3 1.55) (layers "B.Cu" "B.Paste" "B.Mask")
      (net 170 "3V3_SSD") (pinfunction "3V3") (pintype "passive"))
    (pad "19" smd rect locked (at -4.75 3.848 90) (size 0.3 1.55) (layers "B.Cu" "B.Paste" "B.Mask")
      (net 171 "unconnected-(J3-PER2_P-Pad19)") (pinfunction "PER2_P") (pintype "passive+no_connect"))
    (pad "20" smd rect locked (at -4.5 -3.7 90) (size 0.3 1.55) (layers "B.Cu" "B.Paste" "B.Mask")
      (net 172 "unconnected-(J3-NC-Pad20)") (pinfunction "NC") (pintype "no_connect"))
    (pad "21" smd rect locked (at -4.25 3.848 90) (size 0.3 1.55) (layers "B.Cu" "B.Paste" "B.Mask")
      (net 11 "GND") (pinfunction "GND") (pintype "passive"))
    (pad "22" smd rect locked (at -4 -3.7 90) (size 0.3 1.55) (layers "B.Cu" "B.Paste" "B.Mask")
      (net 173 "unconnected-(J3-NC-Pad22)") (pinfunction "NC") (pintype "no_connect"))
    (pad "23" smd rect locked (at -3.75 3.848 90) (size 0.3 1.55) (layers "B.Cu" "B.Paste" "B.Mask")
      (net 174 "unconnected-(J3-PET2_N-Pad23)") (pinfunction "PET2_N") (pintype "passive+no_connect"))
    (pad "24" smd rect locked (at -3.5 -3.7 90) (size 0.3 1.55) (layers "B.Cu" "B.Paste" "B.Mask")
      (net 176 "unconnected-(J3-NC-Pad24)") (pinfunction "NC") (pintype "no_connect"))
    (pad "25" smd rect locked (at -3.25 3.848 90) (size 0.3 1.55) (layers "B.Cu" "B.Paste" "B.Mask")
      (net 177 "unconnected-(J3-PET2_P-Pad25)") (pinfunction "PET2_P") (pintype "passive+no_connect"))
    (pad "26" smd rect locked (at -3 -3.7 90) (size 0.3 1.55) (layers "B.Cu" "B.Paste" "B.Mask")
      (net 178 "unconnected-(J3-NC-Pad26)") (pinfunction "NC") (pintype "no_connect"))
    (pad "27" smd rect locked (at -2.75 3.848 90) (size 0.3 1.55) (layers "B.Cu" "B.Paste" "B.Mask")
      (net 11 "GND") (pinfunction "GND") (pintype "passive"))
    (pad "28" smd rect locked (at -2.5 -3.7 90) (size 0.3 1.55) (layers "B.Cu" "B.Paste" "B.Mask")
      (net 179 "unconnected-(J3-NC-Pad28)") (pinfunction "NC") (pintype "no_connect"))
    (pad "29" smd rect locked (at -2.25 3.848 90) (size 0.3 1.55) (layers "B.Cu" "B.Paste" "B.Mask")
      (net 180 "unconnected-(J3-PER1_N-Pad29)") (pinfunction "PER1_N") (pintype "passive+no_connect"))
    (pad "30" smd rect locked (at -2 -3.7 90) (size 0.3 1.55) (layers "B.Cu" "B.Paste" "B.Mask")
      (net 181 "unconnected-(J3-NC-Pad30)") (pinfunction "NC") (pintype "no_connect"))
    (pad "31" smd rect locked (at -1.75 3.848 90) (size 0.3 1.55) (layers "B.Cu" "B.Paste" "B.Mask")
      (net 182 "unconnected-(J3-PER1_P-Pad31)") (pinfunction "PER1_P") (pintype "passive+no_connect"))
    (pad "32" smd rect locked (at -1.5 -3.7 90) (size 0.3 1.55) (layers "B.Cu" "B.Paste" "B.Mask")
      (net 183 "unconnected-(J3-NC-Pad32)") (pinfunction "NC") (pintype "no_connect"))
    (pad "33" smd rect locked (at -1.25 3.848 90) (size 0.3 1.55) (layers "B.Cu" "B.Paste" "B.Mask")
      (net 11 "GND") (pinfunction "GND") (pintype "passive"))
    (pad "34" smd rect locked (at -1 -3.7 90) (size 0.3 1.55) (layers "B.Cu" "B.Paste" "B.Mask")
      (net 184 "unconnected-(J3-NC-Pad34)") (pinfunction "NC") (pintype "no_connect"))
    (pad "35" smd rect locked (at -0.75 3.848 90) (size 0.3 1.55) (layers "B.Cu" "B.Paste" "B.Mask")
      (net 185 "unconnected-(J3-PET1_N-Pad35)") (pinfunction "PET1_N") (pintype "passive+no_connect"))
    (pad "36" smd rect locked (at -0.5 -3.7 90) (size 0.3 1.55) (layers "B.Cu" "B.Paste" "B.Mask")
      (net 186 "unconnected-(J3-NC-Pad36)") (pinfunction "NC") (pintype "no_connect"))
    (pad "37" smd rect locked (at -0.25 3.848 90) (size 0.3 1.55) (layers "B.Cu" "B.Paste" "B.Mask")
      (net 187 "unconnected-(J3-PET1_P-Pad37)") (pinfunction "PET1_P") (pintype "passive+no_connect"))
    (pad "38" smd rect locked (at 0 -3.7 90) (size 0.3 1.55) (layers "B.Cu" "B.Paste" "B.Mask")
      (net 189 "unconnected-(J3-NC-Pad38)") (pinfunction "NC") (pintype "no_connect"))
    (pad "39" smd rect locked (at 0.246 3.848 90) (size 0.3 1.55) (layers "B.Cu" "B.Paste" "B.Mask")
      (net 11 "GND") (pinfunction "GND") (pintype "passive"))
    (pad "40" smd rect locked (at 0.496 -3.7 90) (size 0.3 1.55) (layers "B.Cu" "B.Paste" "B.Mask")
      (net 190 "unconnected-(J3-SMB_CLK-Pad40)") (pinfunction "SMB_CLK") (pintype "passive+no_connect"))
    (pad "41" smd rect locked (at 0.747 3.848 90) (size 0.3 1.55) (layers "B.Cu" "B.Paste" "B.Mask")
      (net 16 "PCIE_RX_N") (pinfunction "PER0_N") (pintype "passive"))
    (pad "42" smd rect locked (at 0.996 -3.7 90) (size 0.3 1.55) (layers "B.Cu" "B.Paste" "B.Mask")
      (net 192 "unconnected-(J3-SMB_DATA-Pad42)") (pinfunction "SMB_DATA") (pintype "passive+no_connect"))
    (pad "43" smd rect locked (at 1.249 3.848 90) (size 0.3 1.55) (layers "B.Cu" "B.Paste" "B.Mask")
      (net 18 "PCIE_RX_P") (pinfunction "PER0_P") (pintype "passive"))
    (pad "44" smd rect locked (at 1.499 -3.7 90) (size 0.3 1.55) (layers "B.Cu" "B.Paste" "B.Mask")
      (net 193 "unconnected-(J3-ALERT-Pad44)") (pinfunction "ALERT") (pintype "passive+no_connect"))
    (pad "45" smd rect locked (at 1.749 3.848 90) (size 0.3 1.55) (layers "B.Cu" "B.Paste" "B.Mask")
      (net 11 "GND") (pinfunction "GND") (pintype "passive"))
    (pad "46" smd rect locked (at 1.999 -3.7 90) (size 0.3 1.55) (layers "B.Cu" "B.Paste" "B.Mask")
      (net 194 "unconnected-(J3-NC-Pad46)") (pinfunction "NC") (pintype "no_connect"))
    (pad "47" smd rect locked (at 2.249 3.848 90) (size 0.3 1.55) (layers "B.Cu" "B.Paste" "B.Mask")
      (net 15 "PCIE_TX_N") (pinfunction "PET0_N") (pintype "passive"))
    (pad "48" smd rect locked (at 2.499 -3.7 90) (size 0.3 1.55) (layers "B.Cu" "B.Paste" "B.Mask")
      (net 195 "unconnected-(J3-NC-Pad48)") (pinfunction "NC") (pintype "no_connect"))
    (pad "49" smd rect locked (at 2.749 3.848 90) (size 0.3 1.55) (layers "B.Cu" "B.Paste" "B.Mask")
      (net 17 "PCIE_TX_P") (pinfunction "PET0_P") (pintype "passive"))
    (pad "50" smd rect locked (at 2.999 -3.7 90) (size 0.3 1.55) (layers "B.Cu" "B.Paste" "B.Mask")
      (net 99 "PSCIE_nRST") (pinfunction "PERST#") (pintype "passive"))
    (pad "51" smd rect locked (at 3.249 3.848 90) (size 0.3 1.55) (layers "B.Cu" "B.Paste" "B.Mask")
      (net 11 "GND") (pinfunction "GND") (pintype "passive"))
    (pad "52" smd rect locked (at 3.499 -3.7 90) (size 0.3 1.55) (layers "B.Cu" "B.Paste" "B.Mask")
      (net 96 "PCIE_CLK_nREQ") (pinfunction "CLKREQ#") (pintype "passive"))
    (pad "53" smd rect locked (at 3.749 3.848 90) (size 0.3 1.55) (layers "B.Cu" "B.Paste" "B.Mask")
      (net 102 "PCIE_CLK_N") (pinfunction "REFCLK_N") (pintype "passive"))
    (pad "54" smd rect locked (at 3.999 -3.7 90) (size 0.3 1.55) (layers "B.Cu" "B.Paste" "B.Mask")
      (net 162 "PCIE_WAKE") (pinfunction "PEWAKE#") (pintype "passive"))
    (pad "55" smd rect locked (at 4.248 3.848 90) (size 0.3 1.55) (layers "B.Cu" "B.Paste" "B.Mask")
      (net 100 "PCIE_CLK_P") (pinfunction "REFCLK_P") (pintype "passive"))
    (pad "56" smd rect locked (at 4.498 -3.7 90) (size 0.3 1.55) (layers "B.Cu" "B.Paste" "B.Mask")
      (net 196 "unconnected-(J3-NC-Pad56)") (pinfunction "NC") (pintype "no_connect"))
    (pad "57" smd rect locked (at 4.748 3.848 90) (size 0.3 1.55) (layers "B.Cu" "B.Paste" "B.Mask")
      (net 11 "GND") (pinfunction "GND") (pintype "passive"))
    (pad "58" smd rect locked (at 4.998 -3.7 90) (size 0.3 1.55) (layers "B.Cu" "B.Paste" "B.Mask")
      (net 197 "unconnected-(J3-NC-Pad58)") (pinfunction "NC") (pintype "no_connect"))
    (pad "67" smd rect locked (at 7.249 3.848 90) (size 0.3 1.55) (layers "B.Cu" "B.Paste" "B.Mask")
      (net 198 "unconnected-(J3-NC-Pad67)") (pinfunction "NC") (pintype "no_connect"))
    (pad "68" smd rect locked (at 7.498 -3.7 90) (size 0.3 1.55) (layers "B.Cu" "B.Paste" "B.Mask")
      (net 199 "unconnected-(J3-SUSCLK-Pad68)") (pinfunction "SUSCLK") (pintype "passive+no_connect"))
    (pad "69" smd rect locked (at 7.748 3.848 90) (size 0.3 1.55) (layers "B.Cu" "B.Paste" "B.Mask")
      (net 200 "unconnected-(J3-NC-Pad69)") (pinfunction "NC") (pintype "no_connect"))
    (pad "70" smd rect locked (at 7.998 -3.7 90) (size 0.3 1.55) (layers "B.Cu" "B.Paste" "B.Mask")
      (net 170 "3V3_SSD") (pinfunction "3V3") (pintype "passive"))
    (pad "71" smd rect locked (at 8.249 3.848 90) (size 0.3 1.55) (layers "B.Cu" "B.Paste" "B.Mask")
      (net 11 "GND") (pinfunction "GND") (pintype "passive"))
    (pad "72" smd rect locked (at 8.499 -3.7 90) (size 0.3 1.55) (layers "B.Cu" "B.Paste" "B.Mask")
      (net 170 "3V3_SSD") (pinfunction "3V3") (pintype "passive"))
    (pad "73" smd rect locked (at 8.749 3.848 90) (size 0.3 1.55) (layers "B.Cu" "B.Paste" "B.Mask")
      (net 11 "GND") (pinfunction "GND") (pintype "passive"))
    (pad "74" smd rect locked (at 8.999 -3.7 90) (size 0.3 1.55) (layers "B.Cu" "B.Paste" "B.Mask")
      (net 170 "3V3_SSD") (pinfunction "3V3") (pintype "passive"))
    (pad "75" smd rect locked (at 9.249 3.848 90) (size 0.3 1.55) (layers "B.Cu" "B.Paste" "B.Mask")
      (net 11 "GND") (pinfunction "GND") (pintype "passive"))
    (pad "SH1" smd rect locked (at -10.35 3.073 90) (size 1.2 2.75) (layers "B.Cu" "B.Paste" "B.Mask")
      (net 11 "GND") (pinfunction "SHIELD") (pintype "passive"))
    (pad "SH2" smd rect locked (at 10.348 3.073 90) (size 1.2 2.75) (layers "B.Cu" "B.Paste" "B.Mask")
      (net 11 "GND") (pinfunction "SHIELD") (pintype "passive"))
  )
	(footprint "scalenode-cm4-baseboard-footprints:R_0603_1608Metric" (layer "B.Cu")
    (at 177.594 70.146 -90)
    (descr "Resistor SMD 0603")
    (tags "resistor SMD 0603")
    (property "Author" "Antmicro")
    (property "License" "Apache-2.0")
    (property "MPN" "CR0603-FX-1002ELF")
    (property "Manufacturer" "Bourns")
    (property "Sheetfile" "nvme-ssd.kicad_sch")
    (property "Sheetname" "NVMe SSD")
    (property "Tolerance" "1%")
    (property "Val" "10k")
    (property "ki_description" "10k resistor in 0603 package with 1% tolerance")
    (attr smd)
    (fp_text reference "R1" (at 1.471048 -0.377352 90) (layer "B.SilkS")
        (effects (font (size 0.7 0.7) (thickness 0.15)) (justify left bottom mirror))
    )
    (fp_text value "R_10k_0603" (at 0 -1.6 90) (layer "B.Fab")
        (effects (font (size 0.7 0.7) (thickness 0.15)) (justify left bottom mirror))
    )
    (fp_text user "License: Apache-2.0" (at -1.25 -5.9 90) (layer "B.Fab") hide
        (effects (font (size 0.7 0.7) (thickness 0.15)) (justify left bottom mirror))
    )
    (fp_text user "${REFERENCE}" (at -1.25 -3.898 90) (layer "B.Fab") hide
        (effects (font (size 0.7 0.7) (thickness 0.15)) (justify left bottom mirror))
    )
    (fp_text user "Author: Antmicro" (at -1.25 -4.9 90) (layer "B.Fab") hide
        (effects (font (size 0.7 0.7) (thickness 0.15)) (justify left bottom mirror))
    )
    (fp_line (start -0.3 -0.3) (end 0.3 -0.3)
      (stroke (width 0.15) (type solid)) (layer "B.SilkS"))
    (fp_line (start -0.3 0.3) (end 0.3 0.3)
      (stroke (width 0.15) (type solid)) (layer "B.SilkS"))
    (fp_rect (start -1.25 0.7) (end 1.25 -0.7)
      (stroke (width 0.05) (type solid)) (fill none) (layer "B.CrtYd"))
    (fp_rect (start -0.8 0.4) (end 0.8 -0.4)
      (stroke (width 0.15) (type solid)) (fill none) (layer "B.Fab"))
    (pad "1" smd roundrect (at -0.7 0 270) (size 0.6 0.8) (layers "B.Cu" "B.Paste" "B.Mask") (roundrect_rratio 0.2)
      (net 170 "3V3_SSD") (pintype "passive"))
    (pad "2" smd roundrect (at 0.7 0 270) (size 0.6 0.8) (layers "B.Cu" "B.Paste" "B.Mask") (roundrect_rratio 0.2)
      (net 162 "PCIE_WAKE") (pintype "passive"))
  )
	(footprint "scalenode-cm4-baseboard-footprints:C_0603_1608Metric" (layer "B.Cu")
    (at 134.8 93.496 -90)
    (descr "Capacitor SMD 0603")
    (tags "capacitor 0603")
    (property "Author" "Antmicro")
    (property "Dielectric" "")
    (property "License" "Apache-2.0")
    (property "MPN" "GRM188R60J476ME15D")
    (property "Manufacturer" "Murata")
    (property "Sheetfile" "poe.kicad_sch")
    (property "Sheetname" "PoE")
    (property "Val" "47u")
    (property "Voltage" "")
    (property "ki_description" " ")
    (attr smd)
    (fp_text reference "C36" (at -1.071 -1.65 90) (layer "B.SilkS")
        (effects (font (size 0.7 0.7) (thickness 0.15)) (justify left bottom mirror))
    )
    (fp_text value "C_47u_0603" (at -8.371 0.345 90) (layer "B.Fab")
        (effects (font (size 0.7 0.7) (thickness 0.15)) (justify left bottom mirror))
    )
    (fp_text user "${REFERENCE}" (at -1.682 -3.895 90) (layer "B.Fab") hide
        (effects (font (size 0.7 0.7) (thickness 0.15)) (justify left bottom mirror))
    )
    (fp_text user "License: Apache-2.0" (at -1.682 -5.895 90) (layer "B.Fab") hide
        (effects (font (size 0.7 0.7) (thickness 0.15)) (justify left bottom mirror))
    )
    (fp_text user "Author: Antmicro" (at -1.682 -4.894 90) (layer "B.Fab") hide
        (effects (font (size 0.7 0.7) (thickness 0.15)) (justify left bottom mirror))
    )
    (fp_line (start -0.3 -0.3) (end 0.3 -0.3)
      (stroke (width 0.15) (type solid)) (layer "B.SilkS"))
    (fp_line (start -0.3 0.3) (end 0.3 0.3)
      (stroke (width 0.15) (type solid)) (layer "B.SilkS"))
    (fp_rect (start -1.24 0.7) (end 1.24 -0.7)
      (stroke (width 0.05) (type solid)) (fill none) (layer "B.CrtYd"))
    (fp_rect (start -0.8 0.4) (end 0.8 -0.4)
      (stroke (width 0.15) (type solid)) (fill none) (layer "B.Fab"))
    (pad "1" smd roundrect (at -0.7 0 270) (size 0.6 0.8) (layers "B.Cu" "B.Paste" "B.Mask") (roundrect_rratio 0.2)
      (net 11 "GND") (pintype "passive"))
    (pad "2" smd roundrect (at 0.7 0 270) (size 0.6 0.8) (layers "B.Cu" "B.Paste" "B.Mask") (roundrect_rratio 0.2)
      (net 13 "/PoE/VO5V") (pintype "passive"))
  )
)
